(kicad_pcb
	(version 20260206)
	(generator "pcbnew")
	(generator_version "10.0")
	(general
		(thickness 1.6)
		(legacy_teardrops no)
	)
	(paper "A4")
	(title_block
		(title "Bryce Canyon_IOM_M2_16342-2_OCP.brd")
		(comment 1 "Bryce Canyon / footprints 675-681 of 1146")
	)
	(layers
		(0 "F.Cu" signal "TOP")
		(4 "In1.Cu" signal "L2GND")
		(6 "In2.Cu" signal "L3")
		(8 "In3.Cu" signal "L4VCC")
		(10 "In4.Cu" signal "L5VCC")
		(12 "In5.Cu" signal "L6")
		(14 "In6.Cu" signal "L7GND")
		(2 "B.Cu" signal "BOTTOM")
		(9 "F.Adhes" user "F.Adhesive")
		(11 "B.Adhes" user "B.Adhesive")
		(13 "F.Paste" user "Package Geometry/Pastemask Top")
		(15 "B.Paste" user "Package Geometry/Pastemask Bottom")
		(5 "F.SilkS" user "Ref Des/Silkscreen Top")
		(7 "B.SilkS" user "Ref Des/Silkscreen Bottom")
		(1 "F.Mask" user "Board Geometry/Soldermask Top")
		(3 "B.Mask" user "Board Geometry/Soldermask Bottom")
		(17 "Dwgs.User" user "User.Drawings")
		(19 "Cmts.User" user "User.Comments")
		(21 "Eco1.User" user "User.Eco1")
		(23 "Eco2.User" user "User.Eco2")
		(25 "Edge.Cuts" user "Board Geometry/Outline")
		(27 "Margin" user)
		(31 "F.CrtYd" user "Package Geometry/Place Bound Top")
		(29 "B.CrtYd" user "Package Geometry/Place Bound Bottom")
		(35 "F.Fab" user "Ref Des/Assembly Top")
		(33 "B.Fab" user "Ref Des/Assembly Bottom")
	)
	(footprint ""
		(layer "F.Cu")
		(at 94.488 -16.2306 180)
		(property "Reference" "D18"
			(at 0 0 180)
			(layer "F.SilkS")
			(hide yes)
			(effects
				(font
					(size 1.27 1.27)
				)
			)
		)
		(property "Value" "PESD5V0F1BL-GP"
			(at 1.8923 -1.5621 180)
			(unlocked yes)
			(layer "F.Fab")
			(hide yes)
			(effects
				(font
					(size 1.016 1.016)
					(thickness 0.1524)
				)
			)
		)
		(property "Device Type" "SOD882-10D6-1H20"
			(at 1.8923 -3.0861 180)
			(unlocked yes)
			(layer "F.Fab")
			(hide yes)
			(effects
				(font
					(size 1.016 1.016)
					(thickness 0.1524)
				)
			)
		)
		(duplicate_pad_numbers_are_jumpers no)
		(fp_line
			(start -0.3048 -0.9271)
			(end 0.3048 -0.9271)
			(stroke
				(width 0.254)
				(type default)
			)
			(layer "F.SilkS")
		)
		(fp_rect
			(start -0.2921 0.4953)
			(end 0.2921 -0.4953)
			(stroke
				(width 0)
				(type default)
			)
			(fill no)
			(layer "F.CrtYd")
		)
		(fp_poly
			(pts
				(xy -0.4318 0.8001) (xy -0.4318 -0.266192) (xy -0.2921 -0.266192) (xy -0.2921 0.4953) (xy 0.2921 0.4953)
				(xy 0.2921 -0.4953) (xy -0.2921 -0.4953) (xy -0.2921 -0.2667) (xy -0.4318 -0.2667) (xy -0.4318 -0.8001)
				(xy 0.4318 -0.8001) (xy 0.4318 0.8001)
			)
			(stroke
				(width 0)
				(type default)
			)
			(fill no)
			(layer "F.CrtYd")
		)
		(fp_rect
			(start -0.4318 0.8001)
			(end 0.4318 -0.8001)
			(stroke
				(width 0)
				(type default)
			)
			(fill no)
			(layer "F.Fab")
		)
		(pad "1" smd custom
			(at 0 -0.4445 180)
			(size 0.1143 0.1143)
			(layers "F.Cu" "F.Mask" "F.Paste")
			(net "GND")
			(options
				(clearance outline)
				(anchor circle)
			)
			(primitives
				(gr_poly
					(pts
						(arc
							(start -0.2032 0.2286)
							(mid -0.275042 0.198842)
							(end -0.3048 0.127)
						)
						(arc
							(start -0.3048 -0.127)
							(mid -0.275042 -0.198842)
							(end -0.2032 -0.2286)
						)
						(arc
							(start 0.2032 -0.2286)
							(mid 0.275042 -0.198842)
							(end 0.3048 -0.127)
						)
						(arc
							(start 0.3048 0.127)
							(mid 0.275042 0.198842)
							(end 0.2032 0.2286)
						)
					)
					(width 0)
					(fill yes)
				)
			)
		)
		(pad "2" smd custom
			(at 0 0.4445 180)
			(size 0.1143 0.1143)
			(layers "F.Cu" "F.Mask" "F.Paste")
			(net "USB_P1_F_DP1")
			(options
				(clearance outline)
				(anchor circle)
			)
			(primitives
				(gr_poly
					(pts
						(arc
							(start 0.2032 -0.2286)
							(mid 0.275042 -0.198842)
							(end 0.3048 -0.127)
						)
						(arc
							(start 0.3048 0.127)
							(mid 0.275042 0.198842)
							(end 0.2032 0.2286)
						)
						(arc
							(start -0.2032 0.2286)
							(mid -0.275042 0.198842)
							(end -0.3048 0.127)
						)
						(arc
							(start -0.3048 -0.127)
							(mid -0.275042 -0.198842)
							(end -0.2032 -0.2286)
						)
					)
					(width 0)
					(fill yes)
				)
			)
		)
	)
	(footprint ""
		(layer "F.Cu")
		(at 86.994238 -132.679694 180)
		(property "Reference" "R135"
			(at 0 0 180)
			(layer "F.SilkS")
			(hide yes)
			(effects
				(font
					(size 1.27 1.27)
				)
			)
		)
		(property "Value" "8K2R2J-3-GP"
			(at 0.064008 -3.993896 180)
			(unlocked yes)
			(layer "F.Fab")
			(hide yes)
			(effects
				(font
					(size 1.016 1.016)
					(thickness 0.1524)
				)
			)
		)
		(property "Device Type" "R402H16"
			(at 0.064008 -5.517896 180)
			(unlocked yes)
			(layer "F.Fab")
			(hide yes)
			(effects
				(font
					(size 1.016 1.016)
					(thickness 0.1524)
				)
			)
		)
		(duplicate_pad_numbers_are_jumpers no)
		(fp_line
			(start 0.508 -0.9398)
			(end -0.508 -0.9398)
			(stroke
				(width 0.1524)
				(type default)
			)
			(layer "F.SilkS")
		)
		(fp_line
			(start -0.508 -0.9398)
			(end -0.508 0.9398)
			(stroke
				(width 0.1524)
				(type default)
			)
			(layer "F.SilkS")
		)
		(fp_rect
			(start -0.508 0.9398)
			(end 0.508 -0.9398)
			(stroke
				(width 0)
				(type default)
			)
			(fill no)
			(layer "F.CrtYd")
		)
		(fp_rect
			(start -0.508 0.9398)
			(end 0.508 -0.9398)
			(stroke
				(width 0)
				(type default)
			)
			(fill no)
			(layer "F.Fab")
		)
		(pad "1" smd custom
			(at 0 -0.4445 180)
			(size 0.1397 0.1397)
			(layers "F.Cu" "F.Mask" "F.Paste")
			(net "P3V3_STBY")
			(options
				(clearance outline)
				(anchor circle)
			)
			(primitives
				(gr_poly
					(pts
						(arc
							(start -0.1778 -0.2794)
							(mid -0.249642 -0.249642)
							(end -0.2794 -0.1778)
						)
						(arc
							(start -0.2794 0.1778)
							(mid -0.249642 0.249642)
							(end -0.1778 0.2794)
						)
						(arc
							(start 0.1778 0.2794)
							(mid 0.249642 0.249642)
							(end 0.2794 0.1778)
						)
						(arc
							(start 0.2794 -0.1778)
							(mid 0.249642 -0.249642)
							(end 0.1778 -0.2794)
						)
					)
					(width 0)
					(fill yes)
				)
			)
		)
		(pad "2" smd custom
			(at 0 0.4445 180)
			(size 0.1397 0.1397)
			(layers "F.Cu" "F.Mask" "F.Paste")
			(net "EEPROM_A2")
			(options
				(clearance outline)
				(anchor circle)
			)
			(primitives
				(gr_poly
					(pts
						(arc
							(start -0.1778 -0.2794)
							(mid -0.249642 -0.249642)
							(end -0.2794 -0.1778)
						)
						(arc
							(start -0.2794 0.1778)
							(mid -0.249642 0.249642)
							(end -0.1778 0.2794)
						)
						(arc
							(start 0.1778 0.2794)
							(mid 0.249642 0.249642)
							(end 0.2794 0.1778)
						)
						(arc
							(start 0.2794 -0.1778)
							(mid 0.249642 -0.249642)
							(end 0.1778 -0.2794)
						)
					)
					(width 0)
					(fill yes)
				)
			)
		)
	)
	(footprint ""
		(layer "F.Cu")
		(at 148.235416 -10.532618 -90)
		(property "Reference" "R518"
			(at 0 0 270)
			(layer "F.SilkS")
			(hide yes)
			(effects
				(font
					(size 1.27 1.27)
				)
			)
		)
		(property "Value" "10KR2F-2-GP"
			(at 0.064008 -3.993896 270)
			(unlocked yes)
			(layer "F.Fab")
			(hide yes)
			(effects
				(font
					(size 1.016 1.016)
					(thickness 0.1524)
				)
			)
		)
		(property "Device Type" "R402H16"
			(at 0.064008 -5.517896 270)
			(unlocked yes)
			(layer "F.Fab")
			(hide yes)
			(effects
				(font
					(size 1.016 1.016)
					(thickness 0.1524)
				)
			)
		)
		(duplicate_pad_numbers_are_jumpers no)
		(fp_line
			(start -0.508 -0.9398)
			(end -0.508 0.9398)
			(stroke
				(width 0.1524)
				(type default)
			)
			(layer "F.SilkS")
		)
		(fp_line
			(start 0.508 -0.9398)
			(end -0.508 -0.9398)
			(stroke
				(width 0.1524)
				(type default)
			)
			(layer "F.SilkS")
		)
		(fp_rect
			(start -0.508 0.9398)
			(end 0.508 -0.9398)
			(stroke
				(width 0)
				(type default)
			)
			(fill no)
			(layer "F.CrtYd")
		)
		(fp_rect
			(start -0.508 0.9398)
			(end 0.508 -0.9398)
			(stroke
				(width 0)
				(type default)
			)
			(fill no)
			(layer "F.Fab")
		)
		(pad "1" smd custom
			(at 0 -0.4445 270)
			(size 0.1397 0.1397)
			(layers "F.Cu" "F.Mask" "F.Paste")
			(net "P1V8_STBY_VRG5")
			(options
				(clearance outline)
				(anchor circle)
			)
			(primitives
				(gr_poly
					(pts
						(arc
							(start -0.1778 -0.2794)
							(mid -0.249642 -0.249642)
							(end -0.2794 -0.1778)
						)
						(arc
							(start -0.2794 0.1778)
							(mid -0.249642 0.249642)
							(end -0.1778 0.2794)
						)
						(arc
							(start 0.1778 0.2794)
							(mid 0.249642 0.249642)
							(end 0.2794 0.1778)
						)
						(arc
							(start 0.2794 -0.1778)
							(mid 0.249642 -0.249642)
							(end 0.1778 -0.2794)
						)
					)
					(width 0)
					(fill yes)
				)
			)
		)
		(pad "2" smd custom
			(at 0 0.4445 270)
			(size 0.1397 0.1397)
			(layers "F.Cu" "F.Mask" "F.Paste")
			(net "PWRGD_P1V8_STBY")
			(options
				(clearance outline)
				(anchor circle)
			)
			(primitives
				(gr_poly
					(pts
						(arc
							(start -0.1778 -0.2794)
							(mid -0.249642 -0.249642)
							(end -0.2794 -0.1778)
						)
						(arc
							(start -0.2794 0.1778)
							(mid -0.249642 0.249642)
							(end -0.1778 0.2794)
						)
						(arc
							(start 0.1778 0.2794)
							(mid 0.249642 0.249642)
							(end 0.2794 0.1778)
						)
						(arc
							(start 0.2794 -0.1778)
							(mid 0.249642 -0.249642)
							(end 0.1778 -0.2794)
						)
					)
					(width 0)
					(fill yes)
				)
			)
		)
	)
	(footprint ""
		(layer "F.Cu")
		(at 43.675046 -175.72101 -90)
		(property "Reference" "R489"
			(at 0 0 270)
			(layer "F.SilkS")
			(hide yes)
			(effects
				(font
					(size 1.27 1.27)
				)
			)
		)
		(property "Value" "10R3F-GP"
			(at -0.0254 -2.5146 270)
			(unlocked yes)
			(layer "F.Fab")
			(hide yes)
			(effects
				(font
					(size 1.016 1.016)
					(thickness 0.1524)
				)
			)
		)
		(property "Device Type" "R603H22"
			(at -0.0254 -4.0386 270)
			(unlocked yes)
			(layer "F.Fab")
			(hide yes)
			(effects
				(font
					(size 1.016 1.016)
					(thickness 0.1524)
				)
			)
		)
		(duplicate_pad_numbers_are_jumpers no)
		(fp_line
			(start -0.4826 0)
			(end -0.2032 0)
			(stroke
				(width 0.2032)
				(type default)
			)
			(layer "F.SilkS")
		)
		(fp_line
			(start 0.2032 0)
			(end 0.4826 0)
			(stroke
				(width 0.2032)
				(type default)
			)
			(layer "F.SilkS")
		)
		(fp_rect
			(start -0.5842 1.3335)
			(end 0.5842 -1.3335)
			(stroke
				(width 0)
				(type default)
			)
			(fill no)
			(layer "F.CrtYd")
		)
		(fp_rect
			(start -0.5842 1.3335)
			(end 0.5842 -1.3335)
			(stroke
				(width 0)
				(type default)
			)
			(fill no)
			(layer "F.Fab")
		)
		(pad "1" smd custom
			(at 0 -0.762 270)
			(size 0.2159 0.2159)
			(layers "F.Cu" "F.Mask" "F.Paste")
			(net "P3V3_STBY_OUT")
			(options
				(clearance outline)
				(anchor circle)
			)
			(primitives
				(gr_poly
					(pts
						(arc
							(start -0.3302 -0.4318)
							(mid -0.402042 -0.402042)
							(end -0.4318 -0.3302)
						)
						(arc
							(start -0.4318 0.3302)
							(mid -0.402042 0.402042)
							(end -0.3302 0.4318)
						)
						(arc
							(start 0.3302 0.4318)
							(mid 0.402042 0.402042)
							(end 0.4318 0.3302)
						)
						(arc
							(start 0.4318 -0.3302)
							(mid 0.402042 -0.402042)
							(end 0.3302 -0.4318)
						)
					)
					(width 0)
					(fill yes)
				)
			)
		)
		(pad "2" smd custom
			(at 0 0.762 270)
			(size 0.2159 0.2159)
			(layers "F.Cu" "F.Mask" "F.Paste")
			(net "P3V3_STBY_VFB_R")
			(options
				(clearance outline)
				(anchor circle)
			)
			(primitives
				(gr_poly
					(pts
						(arc
							(start -0.3302 -0.4318)
							(mid -0.402042 -0.402042)
							(end -0.4318 -0.3302)
						)
						(arc
							(start -0.4318 0.3302)
							(mid -0.402042 0.402042)
							(end -0.3302 0.4318)
						)
						(arc
							(start 0.3302 0.4318)
							(mid 0.402042 0.402042)
							(end 0.4318 0.3302)
						)
						(arc
							(start 0.4318 -0.3302)
							(mid 0.402042 -0.402042)
							(end 0.3302 -0.4318)
						)
					)
					(width 0)
					(fill yes)
				)
			)
		)
	)
	(footprint ""
		(layer "F.Cu")
		(at 85.504274 -173.615604 180)
		(property "Reference" "C125"
			(at 0 0 180)
			(layer "F.SilkS")
			(hide yes)
			(effects
				(font
					(size 1.27 1.27)
				)
			)
		)
		(property "Value" "SCD1U25V2KX-2-GP"
			(at 1.1811 -2.7051 180)
			(unlocked yes)
			(layer "F.Fab")
			(hide yes)
			(effects
				(font
					(size 1.016 1.016)
					(thickness 0.1524)
				)
			)
		)
		(property "Device Type" "C402H22"
			(at 1.181354 -4.2291 180)
			(unlocked yes)
			(layer "F.Fab")
			(hide yes)
			(effects
				(font
					(size 1.016 1.016)
					(thickness 0.1524)
				)
			)
		)
		(duplicate_pad_numbers_are_jumpers no)
		(fp_rect
			(start -0.4318 0.9525)
			(end 0.4318 -0.9525)
			(stroke
				(width 0)
				(type default)
			)
			(fill no)
			(layer "F.CrtYd")
		)
		(fp_rect
			(start -0.4318 0.9525)
			(end 0.4318 -0.9525)
			(stroke
				(width 0)
				(type default)
			)
			(fill no)
			(layer "F.Fab")
		)
		(pad "1" smd custom
			(at 0 -0.4445 180)
			(size 0.1524 0.1524)
			(layers "F.Cu" "F.Mask" "F.Paste")
			(net "P3V3_STBY")
			(options
				(clearance outline)
				(anchor circle)
			)
			(primitives
				(gr_poly
					(pts
						(arc
							(start 0.3048 -0.2032)
							(mid 0.275042 -0.275042)
							(end 0.2032 -0.3048)
						)
						(arc
							(start -0.2032 -0.3048)
							(mid -0.275042 -0.275042)
							(end -0.3048 -0.2032)
						)
						(arc
							(start -0.3048 0.2032)
							(mid -0.275042 0.275042)
							(end -0.2032 0.3048)
						)
						(arc
							(start 0.2032 0.3048)
							(mid 0.275042 0.275042)
							(end 0.3048 0.2032)
						)
					)
					(width 0)
					(fill yes)
				)
			)
		)
		(pad "2" smd custom
			(at 0 0.4445 180)
			(size 0.1524 0.1524)
			(layers "F.Cu" "F.Mask" "F.Paste")
			(net "GND")
			(options
				(clearance outline)
				(anchor circle)
			)
			(primitives
				(gr_poly
					(pts
						(arc
							(start 0.3048 -0.2032)
							(mid 0.275042 -0.275042)
							(end 0.2032 -0.3048)
						)
						(arc
							(start -0.2032 -0.3048)
							(mid -0.275042 -0.275042)
							(end -0.3048 -0.2032)
						)
						(arc
							(start -0.3048 0.2032)
							(mid -0.275042 0.275042)
							(end -0.2032 0.3048)
						)
						(arc
							(start 0.2032 0.3048)
							(mid 0.275042 0.275042)
							(end 0.3048 0.2032)
						)
					)
					(width 0)
					(fill yes)
				)
			)
		)
	)
	(footprint ""
		(layer "F.Cu")
		(at 39.585646 -177.14341 180)
		(property "Reference" "R482"
			(at 0 0 180)
			(layer "F.SilkS")
			(hide yes)
			(effects
				(font
					(size 1.27 1.27)
				)
			)
		)
		(property "Value" "10KR2J-3-GP"
			(at 0.064008 -3.993896 180)
			(unlocked yes)
			(layer "F.Fab")
			(hide yes)
			(effects
				(font
					(size 1.016 1.016)
					(thickness 0.1524)
				)
			)
		)
		(property "Device Type" "R402H16"
			(at 0.064008 -5.517896 180)
			(unlocked yes)
			(layer "F.Fab")
			(hide yes)
			(effects
				(font
					(size 1.016 1.016)
					(thickness 0.1524)
				)
			)
		)
		(duplicate_pad_numbers_are_jumpers no)
		(fp_line
			(start 0.508 -0.9398)
			(end -0.508 -0.9398)
			(stroke
				(width 0.1524)
				(type default)
			)
			(layer "F.SilkS")
		)
		(fp_line
			(start -0.508 -0.9398)
			(end -0.508 0.9398)
			(stroke
				(width 0.1524)
				(type default)
			)
			(layer "F.SilkS")
		)
		(fp_rect
			(start -0.508 0.9398)
			(end 0.508 -0.9398)
			(stroke
				(width 0)
				(type default)
			)
			(fill no)
			(layer "F.CrtYd")
		)
		(fp_rect
			(start -0.508 0.9398)
			(end 0.508 -0.9398)
			(stroke
				(width 0)
				(type default)
			)
			(fill no)
			(layer "F.Fab")
		)
		(pad "1" smd custom
			(at 0 -0.4445 180)
			(size 0.1397 0.1397)
			(layers "F.Cu" "F.Mask" "F.Paste")
			(net "P12V_STBY")
			(options
				(clearance outline)
				(anchor circle)
			)
			(primitives
				(gr_poly
					(pts
						(arc
							(start -0.1778 -0.2794)
							(mid -0.249642 -0.249642)
							(end -0.2794 -0.1778)
						)
						(arc
							(start -0.2794 0.1778)
							(mid -0.249642 0.249642)
							(end -0.1778 0.2794)
						)
						(arc
							(start 0.1778 0.2794)
							(mid 0.249642 0.249642)
							(end 0.2794 0.1778)
						)
						(arc
							(start 0.2794 -0.1778)
							(mid 0.249642 -0.249642)
							(end 0.1778 -0.2794)
						)
					)
					(width 0)
					(fill yes)
				)
			)
		)
		(pad "2" smd custom
			(at 0 0.4445 180)
			(size 0.1397 0.1397)
			(layers "F.Cu" "F.Mask" "F.Paste")
			(net "P3V3_STBY_EN")
			(options
				(clearance outline)
				(anchor circle)
			)
			(primitives
				(gr_poly
					(pts
						(arc
							(start -0.1778 -0.2794)
							(mid -0.249642 -0.249642)
							(end -0.2794 -0.1778)
						)
						(arc
							(start -0.2794 0.1778)
							(mid -0.249642 0.249642)
							(end -0.1778 0.2794)
						)
						(arc
							(start 0.1778 0.2794)
							(mid 0.249642 0.249642)
							(end 0.2794 0.1778)
						)
						(arc
							(start 0.2794 -0.1778)
							(mid 0.249642 -0.249642)
							(end 0.1778 -0.2794)
						)
					)
					(width 0)
					(fill yes)
				)
			)
		)
	)
	(footprint ""
		(layer "F.Cu")
		(at 222.499936 -187.999878)
		(property "Reference" ""
			(at 0 0 0)
			(layer "F.SilkS")
			(hide yes)
			(effects
				(font
					(size 1.27 1.27)
				)
			)
		)
		(property "Value" "*"
			(at -6.38175 0.19685 0)
			(unlocked yes)
			(layer "F.Fab")
			(hide yes)
			(effects
				(font
					(size 1.016 1.016)
					(thickness 0.1524)
				)
			)
		)
		(duplicate_pad_numbers_are_jumpers no)
		(fp_poly
			(pts
				(arc
					(start 5.0673 0)
					(mid -5.0673 0)
					(end 5.0673 0)
				)
			)
			(stroke
				(width 0)
				(type default)
			)
			(fill no)
			(layer "B.CrtYd")
		)
		(fp_poly
			(pts
				(arc
					(start 5.0673 0)
					(mid -5.0673 0)
					(end 5.0673 0)
				)
			)
			(stroke
				(width 0)
				(type default)
			)
			(fill no)
			(layer "F.CrtYd")
		)
		(fp_poly
			(pts
				(arc
					(start 5.0673 0)
					(mid -5.0673 0)
					(end 5.0673 0)
				)
			)
			(stroke
				(width 0)
				(type default)
			)
			(fill no)
			(layer "B.Fab")
		)
		(fp_poly
			(pts
				(arc
					(start 5.0673 0)
					(mid -5.0673 0)
					(end 5.0673 0)
				)
			)
			(stroke
				(width 0)
				(type default)
			)
			(fill no)
			(layer "F.Fab")
		)
		(pad "1" thru_hole circle
			(at 0 0)
			(size 9.525 9.525)
			(drill 3.5052)
			(layers "*.Cu" "*.Mask")
			(remove_unused_layers no)
			(net "Net_34")
			(clearance -2.5019)
			(thermal_gap 0.3048)
			(padstack
				(mode front_inner_back)
				(layer "Inner"
					(shape circle)
					(size 3.9116 3.9116)
					(clearance 0.3048)
				)
				(layer "B.Cu"
					(shape circle)
					(size 9.525 9.525)
					(clearance -2.5019)
				)
			)
		)
	)
)
